# T6G (Grand Teton) — schematic netlist excerpt (pin names and nets, part order shuffled) for the footprints in the layout excerpt that follows; sources: Cadence DE-HDL packaged netlist, KiCad conversion of 04192023_DAF0TMB3IC0_F0TG_MB_C_brd_V02_OCP.brd

C1213  Q_CAP  22UF 16V 20% X6S  pkg C0805  page 131 : A = P12V_OCP_SFF_R ; B = GND
PC567  Q_CAP  2.2UF 10V 10% X6S  pkg C0402  page 196 : A = PVDDCR_CPU0_P0_VCC5 ; B = GND

(kicad_pcb
	(version 20260206)
	(generator "pcbnew")
	(generator_version "10.0")
	(general
		(thickness 1.6)
		(legacy_teardrops no)
	)
	(paper "A4")
	(title_block
		(title "04192023_DAF0TMB3IC0_F0TG_MB_C_brd_V02_OCP.brd")
		(comment 1 "Grand Teton / footprints 151-153 of 8354")
	)
	(layers
		(0 "F.Cu" signal "TOP")
		(4 "In1.Cu" signal "GND")
		(6 "In2.Cu" signal "IN1")
		(8 "In3.Cu" signal "GND1")
		(10 "In4.Cu" signal "IN2")
		(12 "In5.Cu" signal "GND2")
		(14 "In6.Cu" signal "IN3")
		(16 "In7.Cu" signal "GND3")
		(18 "In8.Cu" signal "VCC")
		(20 "In9.Cu" signal "VCC1")
		(22 "In10.Cu" signal "GND4")
		(24 "In11.Cu" signal "IN4")
		(26 "In12.Cu" signal "GND5")
		(28 "In13.Cu" signal "IN5")
		(30 "In14.Cu" signal "GND6")
		(32 "In15.Cu" signal "IN6")
		(34 "In16.Cu" signal "GND7")
		(2 "B.Cu" signal "BOTTOM")
		(9 "F.Adhes" user "F.Adhesive")
		(11 "B.Adhes" user "B.Adhesive")
		(13 "F.Paste" user "Package Geometry/Pastemask Top")
		(15 "B.Paste" user "Package Geometry/Pastemask Bottom")
		(5 "F.SilkS" user "Ref Des/Silkscreen Top")
		(7 "B.SilkS" user "Ref Des/Silkscreen Bottom")
		(1 "F.Mask" user "Board Geometry/Soldermask Top")
		(3 "B.Mask" user "Board Geometry/Soldermask Bottom")
		(17 "Dwgs.User" user "User.Drawings")
		(19 "Cmts.User" user "User.Comments")
		(21 "Eco1.User" user "User.Eco1")
		(23 "Eco2.User" user "User.Eco2")
		(25 "Edge.Cuts" user "Board Geometry/Outline")
		(27 "Margin" user)
		(31 "F.CrtYd" user "Package Geometry/Place Bound Top")
		(29 "B.CrtYd" user "Package Geometry/Place Bound Bottom")
		(35 "F.Fab" user "Ref Des/Assembly Top")
		(33 "B.Fab" user "Ref Des/Assembly Bottom")
	)
	(footprint ""
		(layer "F.Cu")
		(at 440.333384 -16.014954 180)
		(property "Reference" "C1213"
			(at 0 0 180)
			(layer "F.SilkS")
			(hide yes)
			(effects
				(font
					(size 1.27 1.27)
				)
			)
		)
		(property "Value" ""
			(at 0 0 180)
			(layer "F.Fab")
			(effects
				(font
					(size 1.27 1.27)
				)
			)
		)
		(duplicate_pad_numbers_are_jumpers no)
		(fp_line
			(start 1.524 0.762)
			(end -1.524 0.762)
			(stroke
				(width 0.1524)
				(type default)
			)
			(layer "F.SilkS")
		)
		(fp_line
			(start 1.524 -0.762)
			(end 1.524 0.762)
			(stroke
				(width 0.1524)
				(type default)
			)
			(layer "F.SilkS")
		)
		(fp_line
			(start -1.524 0.762)
			(end -1.524 -0.762)
			(stroke
				(width 0.1524)
				(type default)
			)
			(layer "F.SilkS")
		)
		(fp_line
			(start -1.524 -0.762)
			(end 1.524 -0.762)
			(stroke
				(width 0.1524)
				(type default)
			)
			(layer "F.SilkS")
		)
		(fp_line
			(start 1.1049 0.724916)
			(end 1.1049 -0.724916)
			(stroke
				(width 0.1)
				(type default)
			)
			(layer "F.Fab")
		)
		(fp_line
			(start 1.1049 -0.724916)
			(end -1.1049 -0.724916)
			(stroke
				(width 0.1)
				(type default)
			)
			(layer "F.Fab")
		)
		(fp_line
			(start -1.1049 0.724916)
			(end 1.1049 0.724916)
			(stroke
				(width 0.1)
				(type default)
			)
			(layer "F.Fab")
		)
		(fp_line
			(start -1.1049 -0.724916)
			(end -1.1049 0.724916)
			(stroke
				(width 0.1)
				(type default)
			)
			(layer "F.Fab")
		)
		(pad "1" smd rect
			(at -0.889 0)
			(size 1.016 1.27)
			(layers "F.Cu" "F.Mask" "F.Paste")
			(net "P12V_OCP_SFF_R")
		)
		(pad "2" smd rect
			(at 0.889 0)
			(size 1.016 1.27)
			(layers "F.Cu" "F.Mask" "F.Paste")
			(net "GND")
		)
	)
	(footprint ""
		(layer "F.Cu")
		(at 398.473168 -45.272706 180)
		(property "Reference" ""
			(at 0 0 180)
			(layer "F.SilkS")
			(hide yes)
			(effects
				(font
					(size 1.27 1.27)
				)
			)
		)
		(property "Value" ""
			(at 0 0 180)
			(layer "F.Fab")
			(effects
				(font
					(size 1.27 1.27)
				)
			)
		)
		(duplicate_pad_numbers_are_jumpers no)
		(pad "1" smd circle
			(at 0 0 180)
			(size 0.9906 0.9906)
			(layers "F.Cu" "F.Mask" "F.Paste")
			(net "Net_2239")
		)
		(zone
			(layer "F.Cu")
			(hatch none 0.5)
			(connect_pads
				(clearance 0)
			)
			(min_thickness 0.25)
			(keepout
				(tracks not_allowed)
				(vias allowed)
				(pads allowed)
				(copperpour not_allowed)
				(footprints allowed)
			)
			(placement
				(enabled no)
				(sheetname "")
			)
			(fill
				(thermal_gap 0.5)
				(thermal_bridge_width 0.5)
				(island_removal_mode 0)
			)
			(polygon
				(pts
					(arc
						(start 400.098768 -45.272706)
						(mid 396.847568 -45.272706)
						(end 400.098768 -45.272706)
					)
				)
			)
		)
	)
	(footprint ""
		(layer "F.Cu")
		(at 359.716578 -166.830756 -90)
		(property "Reference" "PC567"
			(at 0 0 270)
			(layer "F.SilkS")
			(hide yes)
			(effects
				(font
					(size 1.27 1.27)
				)
			)
		)
		(property "Value" ""
			(at 0 0 270)
			(layer "F.Fab")
			(effects
				(font
					(size 1.27 1.27)
				)
			)
		)
		(duplicate_pad_numbers_are_jumpers no)
		(fp_line
			(start -0.7874 0.4064)
			(end -0.7874 -0.4064)
			(stroke
				(width 0.1524)
				(type default)
			)
			(layer "F.SilkS")
		)
		(fp_line
			(start -0.199644 0.4064)
			(end -0.7874 0.4064)
			(stroke
				(width 0.1524)
				(type default)
			)
			(layer "F.SilkS")
		)
		(fp_line
			(start 0.7874 0.4064)
			(end 0.409956 0.4064)
			(stroke
				(width 0.1524)
				(type default)
			)
			(layer "F.SilkS")
		)
		(fp_line
			(start -0.7874 -0.4064)
			(end 0.7874 -0.4064)
			(stroke
				(width 0.1524)
				(type default)
			)
			(layer "F.SilkS")
		)
		(fp_line
			(start 0.7874 -0.4064)
			(end 0.7874 0.4064)
			(stroke
				(width 0.1524)
				(type default)
			)
			(layer "F.SilkS")
		)
		(fp_line
			(start -0.67945 0.3048)
			(end -0.67945 -0.305054)
			(stroke
				(width 0.1)
				(type default)
			)
			(layer "F.Fab")
		)
		(fp_line
			(start -0.12065 0.3048)
			(end -0.67945 0.3048)
			(stroke
				(width 0.1)
				(type default)
			)
			(layer "F.Fab")
		)
		(fp_line
			(start 0.120396 0.3048)
			(end 0.120396 0.2794)
			(stroke
				(width 0.1)
				(type default)
			)
			(layer "F.Fab")
		)
		(fp_line
			(start 0.67945 0.3048)
			(end 0.120396 0.3048)
			(stroke
				(width 0.1)
				(type default)
			)
			(layer "F.Fab")
		)
		(fp_line
			(start -0.12065 0.2794)
			(end -0.12065 0.3048)
			(stroke
				(width 0.1)
				(type default)
			)
			(layer "F.Fab")
		)
		(fp_line
			(start 0.120396 0.2794)
			(end -0.12065 0.2794)
			(stroke
				(width 0.1)
				(type default)
			)
			(layer "F.Fab")
		)
		(fp_line
			(start -0.12065 -0.2794)
			(end 0.12065 -0.2794)
			(stroke
				(width 0.1)
				(type default)
			)
			(layer "F.Fab")
		)
		(fp_line
			(start 0.12065 -0.2794)
			(end 0.12065 -0.3048)
			(stroke
				(width 0.1)
				(type default)
			)
			(layer "F.Fab")
		)
		(fp_line
			(start 0.12065 -0.3048)
			(end 0.67945 -0.3048)
			(stroke
				(width 0.1)
				(type default)
			)
			(layer "F.Fab")
		)
		(fp_line
			(start 0.67945 -0.3048)
			(end 0.67945 0.3048)
			(stroke
				(width 0.1)
				(type default)
			)
			(layer "F.Fab")
		)
		(fp_line
			(start -0.67945 -0.305054)
			(end -0.12065 -0.305054)
			(stroke
				(width 0.1)
				(type default)
			)
			(layer "F.Fab")
		)
		(fp_line
			(start -0.12065 -0.305054)
			(end -0.12065 -0.2794)
			(stroke
				(width 0.1)
				(type default)
			)
			(layer "F.Fab")
		)
		(pad "1" smd circle
			(at -0.40005 0 270)
			(size 0 0)
			(layers "F.Cu" "F.Mask" "F.Paste")
			(net "PVDDCR_CPU0_P0_VCC5")
		)
		(pad "2" smd circle
			(at 0.40005 0 270)
			(size 0 0)
			(layers "F.Cu" "F.Mask" "F.Paste")
			(net "GND")
		)
	)
)
